(kicad_pcb
	(version 20260206)
	(generator "pcbnew")
	(generator_version "10.0")
	(general
		(thickness 1.6)
		(legacy_teardrops no)
	)
	(paper "A4")
	(title_block
		(title "Wiwynn_Tioga_Pass_MB.brd")
		(comment 1 "Tioga Pass / footprints 1389-1394 of 4770")
	)
	(layers
		(0 "F.Cu" signal "TOP")
		(4 "In1.Cu" signal "L2GND")
		(6 "In2.Cu" signal "L3")
		(8 "In3.Cu" signal "L4GND")
		(10 "In4.Cu" signal "L5")
		(12 "In5.Cu" signal "L6GND")
		(14 "In6.Cu" signal "L7VCC")
		(16 "In7.Cu" signal "L8VCC")
		(18 "In8.Cu" signal "L9GND")
		(20 "In9.Cu" signal "L10")
		(22 "In10.Cu" signal "L11GND")
		(24 "In11.Cu" signal "L12")
		(26 "In12.Cu" signal "L13GND")
		(2 "B.Cu" signal "BOTTOM")
		(9 "F.Adhes" user "F.Adhesive")
		(11 "B.Adhes" user "B.Adhesive")
		(13 "F.Paste" user "Package Geometry/Pastemask Top")
		(15 "B.Paste" user "Package Geometry/Pastemask Bottom")
		(5 "F.SilkS" user "Ref Des/Silkscreen Top")
		(7 "B.SilkS" user "Ref Des/Silkscreen Bottom")
		(1 "F.Mask" user "Board Geometry/Soldermask Top")
		(3 "B.Mask" user "Board Geometry/Soldermask Bottom")
		(17 "Dwgs.User" user "User.Drawings")
		(19 "Cmts.User" user "User.Comments")
		(21 "Eco1.User" user "User.Eco1")
		(23 "Eco2.User" user "User.Eco2")
		(25 "Edge.Cuts" user "Board Geometry/Outline")
		(27 "Margin" user)
		(31 "F.CrtYd" user "Package Geometry/Place Bound Top")
		(29 "B.CrtYd" user "Package Geometry/Place Bound Bottom")
		(35 "F.Fab" user "Ref Des/Assembly Top")
		(33 "B.Fab" user "Ref Des/Assembly Bottom")
	)
	(footprint ""
		(layer "F.Cu")
		(at 16.002 -87.63)
		(property "Reference" "R1D1"
			(at 0 0 0)
			(layer "F.SilkS")
			(hide yes)
			(effects
				(font
					(size 1.27 1.27)
				)
			)
		)
		(property "Value" ""
			(at 0 0 0)
			(layer "F.Fab")
			(effects
				(font
					(size 1.27 1.27)
				)
			)
		)
		(duplicate_pad_numbers_are_jumpers no)
		(fp_rect
			(start -0.2794 0.9906)
			(end 0.2794 -0.1016)
			(stroke
				(width 0)
				(type default)
			)
			(fill no)
			(layer "F.CrtYd")
		)
		(fp_line
			(start -0.2794 -0.1016)
			(end -0.2794 0.9906)
			(stroke
				(width 0.1)
				(type default)
			)
			(layer "F.Fab")
		)
		(fp_line
			(start -0.2794 0.9906)
			(end 0.2794 0.9906)
			(stroke
				(width 0.1)
				(type default)
			)
			(layer "F.Fab")
		)
		(fp_line
			(start 0.2794 -0.1016)
			(end -0.2794 -0.1016)
			(stroke
				(width 0.1)
				(type default)
			)
			(layer "F.Fab")
		)
		(fp_line
			(start 0.2794 0.9906)
			(end 0.2794 -0.1016)
			(stroke
				(width 0.1)
				(type default)
			)
			(layer "F.Fab")
		)
		(pad "1" smd rect
			(at 0 0)
			(size 0.508 0.508)
			(layers "F.Cu" "F.Mask" "F.Paste")
			(net "PWRGD_PVSA_CPU1_R")
		)
		(pad "2" smd rect
			(at 0 0.889)
			(size 0.508 0.508)
			(layers "F.Cu" "F.Mask" "F.Paste")
			(net "PWRGD_PVSA_CPU1")
		)
		(zone
			(layer "F.Cu")
			(hatch none 0.5)
			(connect_pads
				(clearance 0)
			)
			(min_thickness 0.25)
			(keepout
				(tracks not_allowed)
				(vias allowed)
				(pads allowed)
				(copperpour not_allowed)
				(footprints allowed)
			)
			(placement
				(enabled no)
				(sheetname "")
			)
			(fill
				(thermal_gap 0.5)
				(thermal_bridge_width 0.5)
				(island_removal_mode 0)
			)
			(polygon
				(pts
					(xy 15.748 -86.995) (xy 16.256 -86.995) (xy 16.256 -87.376) (xy 15.748 -87.376)
				)
			)
		)
		(zone
			(layer "F.Cu")
			(hatch none 0.5)
			(connect_pads
				(clearance 0)
			)
			(min_thickness 0.25)
			(keepout
				(tracks allowed)
				(vias not_allowed)
				(pads allowed)
				(copperpour not_allowed)
				(footprints allowed)
			)
			(placement
				(enabled no)
				(sheetname "")
			)
			(fill
				(thermal_gap 0.5)
				(thermal_bridge_width 0.5)
				(island_removal_mode 0)
			)
			(polygon
				(pts
					(xy 15.748 -86.995) (xy 16.256 -86.995) (xy 16.256 -87.376) (xy 15.748 -87.376)
				)
			)
		)
	)
	(footprint ""
		(layer "F.Cu")
		(at 80.757268 -3.3528 -90)
		(property "Reference" "C2G9"
			(at 1.848866 0.752348 270)
			(unlocked yes)
			(layer "F.SilkS")
			(effects
				(font
					(size 1.27 0.9652)
					(thickness 0.1524)
				)
			)
		)
		(property "Value" ""
			(at 0 0 270)
			(layer "F.Fab")
			(effects
				(font
					(size 1.27 1.27)
				)
			)
		)
		(duplicate_pad_numbers_are_jumpers no)
		(fp_rect
			(start -0.500126 1.598422)
			(end 0.500126 -0.201422)
			(stroke
				(width 0)
				(type default)
			)
			(fill no)
			(layer "F.CrtYd")
		)
		(fp_line
			(start -0.500126 1.598422)
			(end -0.500126 -0.201422)
			(stroke
				(width 0.1)
				(type default)
			)
			(layer "F.Fab")
		)
		(fp_line
			(start 0.500126 1.598422)
			(end -0.500126 1.598422)
			(stroke
				(width 0.1)
				(type default)
			)
			(layer "F.Fab")
		)
		(fp_line
			(start -0.500126 -0.201422)
			(end 0.500126 -0.201422)
			(stroke
				(width 0.1)
				(type default)
			)
			(layer "F.Fab")
		)
		(fp_line
			(start 0.500126 -0.201422)
			(end 0.500126 1.598422)
			(stroke
				(width 0.1)
				(type default)
			)
			(layer "F.Fab")
		)
		(pad "1" smd rect
			(at 0 0 180)
			(size 0.889 0.9906)
			(layers "F.Cu" "F.Mask" "F.Paste")
			(net "PVDDQ_GHJ")
		)
		(pad "2" smd rect
			(at 0 1.397 180)
			(size 0.889 0.9906)
			(layers "F.Cu" "F.Mask" "F.Paste")
			(net "GND")
		)
		(zone
			(layer "F.Cu")
			(hatch none 0.5)
			(connect_pads
				(clearance 0)
			)
			(min_thickness 0.25)
			(keepout
				(tracks not_allowed)
				(vias allowed)
				(pads allowed)
				(copperpour not_allowed)
				(footprints allowed)
			)
			(placement
				(enabled no)
				(sheetname "")
			)
			(fill
				(thermal_gap 0.5)
				(thermal_bridge_width 0.5)
				(island_removal_mode 0)
			)
			(polygon
				(pts
					(xy 79.804768 -3.8481) (xy 79.804768 -2.8575) (xy 80.312768 -2.8575) (xy 80.312768 -3.8481)
				)
			)
		)
		(zone
			(layer "F.Cu")
			(hatch none 0.5)
			(connect_pads
				(clearance 0)
			)
			(min_thickness 0.25)
			(keepout
				(tracks allowed)
				(vias not_allowed)
				(pads allowed)
				(copperpour not_allowed)
				(footprints allowed)
			)
			(placement
				(enabled no)
				(sheetname "")
			)
			(fill
				(thermal_gap 0.5)
				(thermal_bridge_width 0.5)
				(island_removal_mode 0)
			)
			(polygon
				(pts
					(xy 79.804768 -3.8481) (xy 79.804768 -2.8575) (xy 80.312768 -2.8575) (xy 80.312768 -3.8481)
				)
			)
		)
	)
	(footprint ""
		(layer "F.Cu")
		(at 13.640816 -1.197864 90)
		(property "Reference" "C1G21"
			(at 0 0 90)
			(layer "F.SilkS")
			(hide yes)
			(effects
				(font
					(size 1.27 1.27)
				)
			)
		)
		(property "Value" ""
			(at 0 0 90)
			(layer "F.Fab")
			(effects
				(font
					(size 1.27 1.27)
				)
			)
		)
		(duplicate_pad_numbers_are_jumpers no)
		(fp_poly
			(pts
				(xy 0.3048 -0.1016) (xy 0.3048 0.9906) (xy -0.3048 0.9906) (xy -0.3048 -0.1016)
			)
			(stroke
				(width 0)
				(type default)
			)
			(fill no)
			(layer "F.CrtYd")
		)
		(fp_line
			(start 0.3048 -0.1016)
			(end -0.3048 -0.1016)
			(stroke
				(width 0.1)
				(type default)
			)
			(layer "F.Fab")
		)
		(fp_line
			(start -0.3048 -0.1016)
			(end -0.3048 0.9906)
			(stroke
				(width 0.1)
				(type default)
			)
			(layer "F.Fab")
		)
		(fp_line
			(start 0.3048 0.9906)
			(end 0.3048 -0.1016)
			(stroke
				(width 0.1)
				(type default)
			)
			(layer "F.Fab")
		)
		(fp_line
			(start -0.3048 0.9906)
			(end 0.3048 0.9906)
			(stroke
				(width 0.1)
				(type default)
			)
			(layer "F.Fab")
		)
		(pad "1" smd rect
			(at 0 0 90)
			(size 0.508 0.508)
			(layers "F.Cu" "F.Mask" "F.Paste")
			(net "PWRGD_PVDDQ_GHJ_R")
		)
		(pad "2" smd rect
			(at 0 0.889 90)
			(size 0.508 0.508)
			(layers "F.Cu" "F.Mask" "F.Paste")
			(net "GND")
		)
		(zone
			(layer "F.Cu")
			(hatch none 0.5)
			(connect_pads
				(clearance 0)
			)
			(min_thickness 0.25)
			(keepout
				(tracks allowed)
				(vias not_allowed)
				(pads allowed)
				(copperpour not_allowed)
				(footprints allowed)
			)
			(placement
				(enabled no)
				(sheetname "")
			)
			(fill
				(thermal_gap 0.5)
				(thermal_bridge_width 0.5)
				(island_removal_mode 0)
			)
			(polygon
				(pts
					(xy 13.894816 -0.943864) (xy 13.894816 -1.451864) (xy 14.275816 -1.451864) (xy 14.275816 -0.943864)
				)
			)
		)
		(zone
			(layer "F.Cu")
			(hatch none 0.5)
			(connect_pads
				(clearance 0)
			)
			(min_thickness 0.25)
			(keepout
				(tracks not_allowed)
				(vias allowed)
				(pads allowed)
				(copperpour not_allowed)
				(footprints allowed)
			)
			(placement
				(enabled no)
				(sheetname "")
			)
			(fill
				(thermal_gap 0.5)
				(thermal_bridge_width 0.5)
				(island_removal_mode 0)
			)
			(polygon
				(pts
					(xy 14.275816 -0.943864) (xy 14.275816 -1.451864) (xy 13.894816 -1.451864) (xy 13.894816 -0.943864)
				)
			)
		)
	)
	(footprint ""
		(layer "F.Cu")
		(at 433.832 -14.224 180)
		(property "Reference" "R6W42"
			(at -0.8382 -0.67818 180)
			(unlocked yes)
			(layer "F.SilkS")
			(effects
				(font
					(size 0.4064 0.254)
					(thickness 0.1524)
				)
				(justify left)
			)
		)
		(property "Value" ""
			(at 0 0 180)
			(layer "F.Fab")
			(effects
				(font
					(size 1.27 1.27)
				)
			)
		)
		(duplicate_pad_numbers_are_jumpers no)
		(fp_poly
			(pts
				(xy -0.2794 -0.1016) (xy 0.2794 -0.1016) (xy 0.2794 0.9906) (xy -0.2794 0.9906)
			)
			(stroke
				(width 0)
				(type default)
			)
			(fill no)
			(layer "F.CrtYd")
		)
		(fp_line
			(start 0.2794 0.9906)
			(end 0.2794 -0.1016)
			(stroke
				(width 0.1)
				(type default)
			)
			(layer "F.Fab")
		)
		(fp_line
			(start 0.2794 -0.1016)
			(end -0.2794 -0.1016)
			(stroke
				(width 0.1)
				(type default)
			)
			(layer "F.Fab")
		)
		(fp_line
			(start -0.2794 0.9906)
			(end 0.2794 0.9906)
			(stroke
				(width 0.1)
				(type default)
			)
			(layer "F.Fab")
		)
		(fp_line
			(start -0.2794 -0.1016)
			(end -0.2794 0.9906)
			(stroke
				(width 0.1)
				(type default)
			)
			(layer "F.Fab")
		)
		(pad "1" smd rect
			(at 0 0 180)
			(size 0.508 0.508)
			(layers "F.Cu" "F.Mask" "F.Paste")
			(net "P3V3_STBY")
		)
		(pad "2" smd rect
			(at 0 0.889 180)
			(size 0.508 0.508)
			(layers "F.Cu" "F.Mask" "F.Paste")
			(net "PCA9554_A2")
		)
		(zone
			(layer "F.Cu")
			(hatch none 0.5)
			(connect_pads
				(clearance 0)
			)
			(min_thickness 0.25)
			(keepout
				(tracks not_allowed)
				(vias allowed)
				(pads allowed)
				(copperpour not_allowed)
				(footprints allowed)
			)
			(placement
				(enabled no)
				(sheetname "")
			)
			(fill
				(thermal_gap 0.5)
				(thermal_bridge_width 0.5)
				(island_removal_mode 0)
			)
			(polygon
				(pts
					(xy 434.086 -14.859) (xy 433.578 -14.859) (xy 433.578 -14.478) (xy 434.086 -14.478)
				)
			)
		)
		(zone
			(layer "F.Cu")
			(hatch none 0.5)
			(connect_pads
				(clearance 0)
			)
			(min_thickness 0.25)
			(keepout
				(tracks allowed)
				(vias not_allowed)
				(pads allowed)
				(copperpour not_allowed)
				(footprints allowed)
			)
			(placement
				(enabled no)
				(sheetname "")
			)
			(fill
				(thermal_gap 0.5)
				(thermal_bridge_width 0.5)
				(island_removal_mode 0)
			)
			(polygon
				(pts
					(xy 434.086 -14.478) (xy 433.578 -14.478) (xy 433.578 -14.859) (xy 434.086 -14.859)
				)
			)
		)
	)
	(footprint ""
		(layer "F.Cu")
		(at 346.3671 1.741678 -90)
		(property "Reference" "EU7G3"
			(at 3.675888 2.504694 0)
			(unlocked yes)
			(layer "F.SilkS")
			(effects
				(font
					(size 0.7874 0.5842)
					(thickness 0.1524)
				)
			)
		)
		(property "Value" ""
			(at 0 0 270)
			(layer "F.Fab")
			(effects
				(font
					(size 1.27 1.27)
				)
			)
		)
		(duplicate_pad_numbers_are_jumpers no)
		(fp_line
			(start -3.0099 3.429)
			(end -3.0099 -3.5052)
			(stroke
				(width 0.1524)
				(type default)
			)
			(layer "F.SilkS")
		)
		(fp_line
			(start 2.9718 3.429)
			(end -3.0099 3.429)
			(stroke
				(width 0.1524)
				(type default)
			)
			(layer "F.SilkS")
		)
		(fp_line
			(start -3.0099 -3.5052)
			(end 2.9718 -3.5052)
			(stroke
				(width 0.1524)
				(type default)
			)
			(layer "F.SilkS")
		)
		(fp_line
			(start 2.9718 -3.5052)
			(end 2.9718 3.429)
			(stroke
				(width 0.1524)
				(type default)
			)
			(layer "F.SilkS")
		)
		(fp_circle
			(center -3.057398 -2.678684)
			(end -3.057398 -2.805684)
			(stroke
				(width 0.254)
				(type default)
			)
			(fill no)
			(layer "F.SilkS")
		)
		(fp_poly
			(pts
				(xy -2.9972 -3.4925) (xy -2.9972 -2.6924) (xy -2.1971 -3.4925)
			)
			(stroke
				(width 0)
				(type default)
			)
			(fill yes)
			(layer "F.SilkS")
		)
		(fp_poly
			(pts
				(xy -2.549906 -3.050032) (xy -2.549906 3.050032) (xy 2.549906 3.050032) (xy 2.549906 -3.050032)
			)
			(stroke
				(width 0)
				(type default)
			)
			(fill no)
			(layer "F.CrtYd")
		)
		(fp_line
			(start -2.549906 3.050032)
			(end -2.549906 -3.050032)
			(stroke
				(width 0.1)
				(type default)
			)
			(layer "F.Fab")
		)
		(fp_line
			(start 2.549906 3.050032)
			(end -2.549906 3.050032)
			(stroke
				(width 0.1)
				(type default)
			)
			(layer "F.Fab")
		)
		(fp_line
			(start -2.549906 -3.050032)
			(end 2.549906 -3.050032)
			(stroke
				(width 0.1)
				(type default)
			)
			(layer "F.Fab")
		)
		(fp_line
			(start 2.549906 -3.050032)
			(end 2.549906 3.050032)
			(stroke
				(width 0.1)
				(type default)
			)
			(layer "F.Fab")
		)
		(fp_circle
			(center -3.057398 -2.678684)
			(end -3.057398 -2.805684)
			(stroke
				(width 0.254)
				(type default)
			)
			(fill no)
			(layer "F.Fab")
		)
		(pad "1" smd rect
			(at -2.39522 -2.279904 270)
			(size 0.7112 0.254)
			(layers "F.Cu" "F.Mask" "F.Paste")
			(net "PVDDQ_ABC")
		)
		(pad "2" smd rect
			(at -2.39522 -1.83007 270)
			(size 0.7112 0.254)
			(layers "F.Cu" "F.Mask" "F.Paste")
			(net "GND")
		)
		(pad "3" smd rect
			(at -2.39522 -1.379982 270)
			(size 0.7112 0.254)
			(layers "F.Cu" "F.Mask" "F.Paste")
			(net "VR_PVDDQ_ABC_PH2_VCIN")
		)
		(pad "4" smd rect
			(at -2.39522 -0.929894 270)
			(size 0.7112 0.254)
			(layers "F.Cu" "F.Mask" "F.Paste")
			(net "P5V_STBY")
		)
		(pad "5" smd rect
			(at -2.39522 -0.48006 270)
			(size 0.7112 0.254)
			(layers "F.Cu" "F.Mask" "F.Paste")
			(net "GND")
		)
		(pad "6" smd rect
			(at -2.39522 -0.029972 270)
			(size 0.7112 0.254)
			(layers "F.Cu" "F.Mask" "F.Paste")
			(net "TP_PVDDQ_ABC_PH2_GL_0")
		)
		(pad "7" smd custom
			(at 0.016764 1.145032 270)
			(size 0.53975 0.53975)
			(layers "F.Cu" "F.Mask" "F.Paste")
			(net "GND")
			(options
				(clearance outline)
				(anchor circle)
			)
			(primitives
				(gr_poly
					(pts
						(xy -2.7051 1.0795) (xy -2.7051 -0.3683) (xy -0.9271 -0.3683) (xy -0.9271 -1.0795) (xy 2.7051 -1.0795)
						(xy 2.7051 1.0795)
					)
					(width 0)
					(fill yes)
				)
			)
		)
		(pad "10" smd rect
			(at -0.008382 2.874772 270)
			(size 4.3434 0.6096)
			(layers "F.Cu" "F.Mask" "F.Paste")
			(net "VR_PVDDQ_ABC_PH2_SW")
		)
		(pad "25" smd rect
			(at 1.548384 -1.283208 270)
			(size 2.3368 2.0066)
			(layers "F.Cu" "F.Mask" "F.Paste")
			(net "VR_FET_SW_P12V_STBY_PVDDQ_ABC")
		)
		(pad "30" smd rect
			(at 2.050034 -2.895092 270)
			(size 0.254 0.7112)
			(layers "F.Cu" "F.Mask" "F.Paste")
			(net "VR_FET_SW_P12V_STBY_PVDDQ_ABC")
		)
		(pad "31" smd rect
			(at 1.599946 -2.895092 270)
			(size 0.254 0.7112)
			(layers "F.Cu" "F.Mask" "F.Paste")
			(net "Net_369")
		)
		(pad "32" smd rect
			(at 1.150112 -2.895092 270)
			(size 0.254 0.7112)
			(layers "F.Cu" "F.Mask" "F.Paste")
			(net "VR_PVDDQ_ABC_PH2_PHASE")
		)
		(pad "33" smd rect
			(at 0.700024 -2.895092 270)
			(size 0.254 0.7112)
			(layers "F.Cu" "F.Mask" "F.Paste")
			(net "VR_PVDDQ_ABC_PH2_BOOT_R")
		)
		(pad "34" smd rect
			(at 0.249936 -2.895092 270)
			(size 0.254 0.7112)
			(layers "F.Cu" "F.Mask" "F.Paste")
			(net "VR_PVDDQ_ABC_PWM2")
		)
		(pad "35" smd rect
			(at -0.199898 -2.895092 270)
			(size 0.254 0.7112)
			(layers "F.Cu" "F.Mask" "F.Paste")
			(net "P5V_STBY")
		)
		(pad "36" smd rect
			(at -0.649986 -2.895092 270)
			(size 0.254 0.7112)
			(layers "F.Cu" "F.Mask" "F.Paste")
			(net "A_TSENSE_PVDDQ_ABC")
		)
		(pad "37" smd rect
			(at -1.100074 -2.895092 270)
			(size 0.254 0.7112)
			(layers "F.Cu" "F.Mask" "F.Paste")
			(net "VR_PVDDQ_ABC_PH2_OCSET")
		)
		(pad "38" smd rect
			(at -1.549908 -2.895092 270)
			(size 0.254 0.7112)
			(layers "F.Cu" "F.Mask" "F.Paste")
			(net "ISENSE_PVDDQ_ABC_PH2_IMON")
		)
		(pad "39" smd rect
			(at -1.999996 -2.895092 270)
			(size 0.254 0.7112)
			(layers "F.Cu" "F.Mask" "F.Paste")
			(net "VR_PVDDQ_ABC_AIREF2")
		)
		(pad "40" smd rect
			(at -0.871728 -1.283208 270)
			(size 1.8034 2.0066)
			(layers "F.Cu" "F.Mask" "F.Paste")
			(net "GND")
		)
		(pad "41" smd rect
			(at -1.533906 0.247904 270)
			(size 0.508 0.3556)
			(layers "F.Cu" "F.Mask" "F.Paste")
			(net "TP_PVDDQ_ABC_PH2_GL_1")
		)
	)
	(footprint ""
		(layer "F.Cu")
		(at 10.166096 -124.854208 -90)
		(property "Reference" "R12W17"
			(at 0 0 270)
			(layer "F.SilkS")
			(hide yes)
			(effects
				(font
					(size 1.27 1.27)
				)
			)
		)
		(property "Value" "*"
			(at 0 -8.9535 270)
			(unlocked yes)
			(layer "F.Fab")
			(hide yes)
			(effects
				(font
					(size 1.27 1.016)
					(thickness 0.1524)
				)
			)
		)
		(property "Device Type" "665KR5B-1-GP_SMD-RG3-665KR5B-1A"
			(at 0 -10.6299 270)
			(unlocked yes)
			(layer "F.Fab")
			(hide yes)
			(effects
				(font
					(size 1.27 1.016)
					(thickness 0.1524)
				)
			)
		)
		(duplicate_pad_numbers_are_jumpers no)
		(fp_line
			(start -0.889 1.7018)
			(end 0.889 1.7018)
			(stroke
				(width 0.1524)
				(type default)
			)
			(layer "F.SilkS")
		)
		(fp_line
			(start 0.889 1.7018)
			(end 0.889 -0.508)
			(stroke
				(width 0.1524)
				(type default)
			)
			(layer "F.SilkS")
		)
		(fp_line
			(start -0.889 0.0762)
			(end -0.889 1.7018)
			(stroke
				(width 0.1524)
				(type default)
			)
			(layer "F.SilkS")
		)
		(fp_line
			(start -0.889 -1.7018)
			(end -0.889 0.2794)
			(stroke
				(width 0.1524)
				(type default)
			)
			(layer "F.SilkS")
		)
		(fp_line
			(start 0.889 -1.7018)
			(end 0.889 -0.381)
			(stroke
				(width 0.1524)
				(type default)
			)
			(layer "F.SilkS")
		)
		(fp_line
			(start 0.889 -1.7018)
			(end -0.889 -1.7018)
			(stroke
				(width 0.1524)
				(type default)
			)
			(layer "F.SilkS")
		)
		(fp_poly
			(pts
				(xy 0.9652 -1.778) (xy 0.9652 1.778) (xy -0.9652 1.778) (xy -0.9652 -1.778)
			)
			(stroke
				(width 0)
				(type default)
			)
			(fill no)
			(layer "F.CrtYd")
		)
		(fp_rect
			(start -0.9652 1.778)
			(end 0.9652 -1.778)
			(stroke
				(width 0)
				(type default)
			)
			(fill no)
			(layer "F.Fab")
		)
		(pad "1" smd rect
			(at 0 -0.9652 270)
			(size 1.397 1.143)
			(layers "F.Cu" "F.Mask" "F.Paste")
			(net "P12V_NVDIMM_KLM_D")
		)
		(pad "2" smd rect
			(at 0 0.9652 270)
			(size 1.397 1.143)
			(layers "F.Cu" "F.Mask" "F.Paste")
			(net "VR_PVDDQ_KLM_VINSEN")
		)
	)
)
